(kicad_pcb
	(version 20241229)
	(generator "pcbnew")
	(generator_version "9.0")
	(general
		(thickness 1.61)
		(legacy_teardrops no)
	)
	(paper "A3")
	(title_block
		(title "RDIMM DDR5 Tester")
		(date "2026-05-21")
		(rev "2.2.0")
		(company "Antmicro")
		(comment 9 "footprints 230-234 of 796")
	)
	(layers
		(0 "F.Cu" signal)
		(4 "In1.Cu" power)
		(6 "In2.Cu" mixed)
		(8 "In3.Cu" power)
		(10 "In4.Cu" mixed)
		(12 "In5.Cu" power)
		(14 "In6.Cu" mixed)
		(16 "In7.Cu" power)
		(18 "In8.Cu" power)
		(20 "In9.Cu" mixed)
		(22 "In10.Cu" power)
		(2 "B.Cu" signal)
		(9 "F.Adhes" user "F.Adhesive")
		(11 "B.Adhes" user "B.Adhesive")
		(13 "F.Paste" user)
		(15 "B.Paste" user)
		(5 "F.SilkS" user "F.Silkscreen")
		(7 "B.SilkS" user "B.Silkscreen")
		(1 "F.Mask" user)
		(3 "B.Mask" user)
		(17 "Dwgs.User" user "User.Drawings")
		(19 "Cmts.User" user "User.Comments")
		(21 "Eco1.User" user "User.Eco1")
		(23 "Eco2.User" user "User.Eco2")
		(25 "Edge.Cuts" user)
		(27 "Margin" user)
		(31 "F.CrtYd" user "F.Courtyard")
		(29 "B.CrtYd" user "B.Courtyard")
		(35 "F.Fab" user)
		(33 "B.Fab" user)
	)
	(footprint "antmicro-footprints:Vishay_PowerPAK_1212-8_Single"
		(layer "F.Cu")
		(at 247.255 115.74 90)
		(descr "PowerPAK 1212-8 Single")
		(tags "Vishay PowerPAK 1212-8 Single")
		(property "Reference" "Q23"
			(at -2.16 1.845 0)
			(layer "F.SilkS")
			(effects
				(font
					(size 0.7 0.7)
					(thickness 0.15)
				)
				(justify right top)
			)
		)
		(property "Value" "SI7613DN-T1-GE3"
			(at 0 2.7 90)
			(layer "F.Fab")
			(effects
				(font
					(size 0.7 0.7)
					(thickness 0.15)
				)
				(justify left bottom)
			)
		)
		(property "Datasheet" "https://www.vishay.com/docs/64809/si7613dn.pdf"
			(at 0 0 90)
			(layer "F.Fab")
			(hide yes)
			(effects
				(font
					(size 1.27 1.27)
					(thickness 0.15)
				)
			)
		)
		(property "MPN" "SI7613DN-T1-GE3"
			(at 0 0 90)
			(unlocked yes)
			(layer "F.Fab")
			(hide yes)
			(effects
				(font
					(size 1 1)
					(thickness 0.15)
				)
			)
		)
		(property "Manufacturer" "Vishay"
			(at 0 0 90)
			(unlocked yes)
			(layer "F.Fab")
			(hide yes)
			(effects
				(font
					(size 1 1)
					(thickness 0.15)
				)
			)
		)
		(property "Author" "Antmicro"
			(at 0 0 90)
			(unlocked yes)
			(layer "F.Fab")
			(hide yes)
			(effects
				(font
					(size 1 1)
					(thickness 0.15)
				)
			)
		)
		(property "License" "Apache-2.0"
			(at 0 0 90)
			(unlocked yes)
			(layer "F.Fab")
			(hide yes)
			(effects
				(font
					(size 1 1)
					(thickness 0.15)
				)
			)
		)
		(sheetname "/DDR5 RDIMM/")
		(sheetfile "ddr5-rdimm.kicad_sch")
		(attr smd)
		(fp_line
			(start 1.648 -1.651)
			(end 1.648 -1.317)
			(stroke
				(width 0.15)
				(type solid)
			)
			(layer "F.SilkS")
		)
		(fp_line
			(start -1.651 -1.651)
			(end 1.648 -1.651)
			(stroke
				(width 0.15)
				(type solid)
			)
			(layer "F.SilkS")
		)
		(fp_line
			(start -1.651 -1.651)
			(end -1.651 -1.317)
			(stroke
				(width 0.15)
				(type solid)
			)
			(layer "F.SilkS")
		)
		(fp_line
			(start 1.634 1.3)
			(end 1.634 1.634)
			(stroke
				(width 0.15)
				(type solid)
			)
			(layer "F.SilkS")
		)
		(fp_line
			(start -1.635 1.3)
			(end -1.635 1.634)
			(stroke
				(width 0.15)
				(type solid)
			)
			(layer "F.SilkS")
		)
		(fp_line
			(start -1.635 1.634)
			(end 1.634 1.634)
			(stroke
				(width 0.15)
				(type solid)
			)
			(layer "F.SilkS")
		)
		(fp_circle
			(center -1.9 -1.4)
			(end -1.85 -1.4)
			(stroke
				(width 0.15)
				(type solid)
			)
			(fill yes)
			(layer "F.SilkS")
		)
		(fp_rect
			(start -2 -1.8)
			(end 2 1.798)
			(stroke
				(width 0.05)
				(type solid)
			)
			(fill no)
			(layer "F.CrtYd")
		)
		(fp_line
			(start -1.6425 -1.4175)
			(end -1.4175 -1.6425)
			(stroke
				(width 0.15)
				(type solid)
			)
			(layer "F.Fab")
		)
		(fp_rect
			(start -1.651 -1.651)
			(end 1.648 1.648)
			(stroke
				(width 0.15)
				(type solid)
			)
			(fill no)
			(layer "F.Fab")
		)
		(fp_text user "License: Apache-2.0"
			(at -8 7.1 90)
			(layer "F.Fab")
			(effects
				(font
					(size 0.7 0.7)
					(thickness 0.15)
				)
				(justify left bottom)
			)
		)
		(fp_text user "${REFERENCE}"
			(at -8 4.7 90)
			(layer "F.Fab")
			(effects
				(font
					(size 0.7 0.7)
					(thickness 0.15)
				)
				(justify left bottom)
			)
		)
		(fp_text user "Author: Antmicro"
			(at -8 5.9 90)
			(layer "F.Fab")
			(effects
				(font
					(size 0.7 0.7)
					(thickness 0.15)
				)
				(justify left bottom)
			)
		)
		(pad "1" smd rect
			(at -1.436 -0.99 90)
			(size 0.99 0.405)
			(layers "F.Cu" "F.Mask" "F.Paste")
			(net 35 "VDC")
			(pinfunction "S")
			(pintype "passive")
		)
		(pad "2" smd rect
			(at -1.436 -0.332 90)
			(size 0.99 0.405)
			(layers "F.Cu" "F.Mask" "F.Paste")
			(net 35 "VDC")
			(pinfunction "S")
			(pintype "passive")
		)
		(pad "3" smd rect
			(at -1.436 0.33 90)
			(size 0.99 0.405)
			(layers "F.Cu" "F.Mask" "F.Paste")
			(net 35 "VDC")
			(pinfunction "S")
			(pintype "passive")
		)
		(pad "4" smd rect
			(at -1.436 0.988 90)
			(size 0.99 0.405)
			(layers "F.Cu" "F.Mask" "F.Paste")
			(net 806 "Net-(Q23-G)")
			(pinfunction "G")
			(pintype "passive")
		)
		(pad "5" smd custom
			(at 0.557 0 90)
			(size 1.725 2.235)
			(layers "F.Cu" "F.Mask" "F.Paste")
			(net 802 "/DDR5 RDIMM/VIN_BULK")
			(pinfunction "D")
			(pintype "passive")
			(zone_connect 2)
			(options
				(clearance outline)
				(anchor rect)
			)
			(primitives
				(gr_poly
					(pts
						(xy 0.8625 0.1275) (xy 0.8625 -0.1275) (xy 1.3725 -0.1275) (xy 1.3725 -0.5325) (xy 0.8625 -0.5325)
						(xy 0.8625 -0.7875) (xy 1.3725 -0.7875) (xy 1.3725 -1.195) (xy 0.6125 -1.195) (xy 0.6125 1.195)
						(xy 1.3725 1.195) (xy 1.3725 0.7875) (xy 0.8625 0.7875) (xy 0.8625 0.5325) (xy 1.3725 0.5325)
						(xy 1.3725 0.1275)
					)
					(width 0)
					(fill yes)
				)
			)
		)
	)
	(footprint "antmicro-footprints:TP_SMD_1mm"
		(layer "F.Cu")
		(at 244.05 155.925)
		(property "Reference" "TP12"
			(at 0 -0.731898 0)
			(layer "F.SilkS")
			(hide yes)
			(effects
				(font
					(size 0.7 0.7)
					(thickness 0.15)
				)
				(justify left bottom)
			)
		)
		(property "Value" "TP_1mm_SMD"
			(at 0 1.4 0)
			(layer "F.Fab")
			(effects
				(font
					(size 0.7 0.7)
					(thickness 0.15)
				)
				(justify left bottom)
			)
		)
		(property "MPN" ""
			(at 0 0 0)
			(unlocked yes)
			(layer "F.Fab")
			(hide yes)
			(effects
				(font
					(size 1 1)
					(thickness 0.15)
				)
			)
		)
		(property "Manufacturer" ""
			(at 0 0 0)
			(unlocked yes)
			(layer "F.Fab")
			(hide yes)
			(effects
				(font
					(size 1 1)
					(thickness 0.15)
				)
			)
		)
		(property "Author" "Antmicro"
			(at 0 0 0)
			(unlocked yes)
			(layer "F.Fab")
			(hide yes)
			(effects
				(font
					(size 1 1)
					(thickness 0.15)
				)
			)
		)
		(property "License" "Apache-2.0"
			(at 0 0 0)
			(unlocked yes)
			(layer "F.Fab")
			(hide yes)
			(effects
				(font
					(size 1 1)
					(thickness 0.15)
				)
			)
		)
		(sheetname "/Supply/DC-DC IO/")
		(sheetfile "dc-dc-io.kicad_sch")
		(attr exclude_from_pos_files)
		(fp_circle
			(center 0 0)
			(end 0.6 0)
			(stroke
				(width 0.05)
				(type default)
			)
			(fill no)
			(layer "F.CrtYd")
		)
		(fp_text user "${REFERENCE}"
			(at -0.5 2.8 0)
			(layer "F.Fab")
			(effects
				(font
					(size 0.7 0.7)
					(thickness 0.15)
				)
				(justify left bottom)
			)
		)
		(fp_text user "Author: Antmicro"
			(at -0.5 4 0)
			(layer "F.Fab")
			(effects
				(font
					(size 0.7 0.7)
					(thickness 0.15)
				)
				(justify left bottom)
			)
		)
		(fp_text user "License: Apache-2.0"
			(at -0.5 5.2 0)
			(layer "F.Fab")
			(effects
				(font
					(size 0.7 0.7)
					(thickness 0.15)
				)
				(justify left bottom)
			)
		)
		(pad "1" smd circle
			(at 0 0)
			(size 1 1)
			(layers "F.Cu" "F.Mask")
			(net 151 "+3V3")
			(pinfunction "1")
			(pintype "passive")
		)
	)
	(footprint "antmicro-footprints:R_0402_1005Metric"
		(layer "F.Cu")
		(at 119.15 147.61 180)
		(descr "Resistor SMD 0402")
		(tags "resistor SMD 0402")
		(property "Reference" "R30"
			(at -5.12 -0.42 0)
			(layer "F.SilkS")
			(effects
				(font
					(size 0.7 0.7)
					(thickness 0.15)
				)
				(justify right bottom)
			)
		)
		(property "Value" "R_49k9_0402"
			(at -1.011843 1.772047 0)
			(layer "F.Fab")
			(effects
				(font
					(size 0.7 0.7)
					(thickness 0.15)
				)
				(justify right bottom)
			)
		)
		(property "Datasheet" "https://www.bourns.com/docs/product-datasheets/cr.pdf"
			(at 0 0 180)
			(layer "F.Fab")
			(hide yes)
			(effects
				(font
					(size 1.27 1.27)
					(thickness 0.15)
				)
			)
		)
		(property "MPN" "CR0402-FX-4992GLF"
			(at 0 0 180)
			(unlocked yes)
			(layer "F.Fab")
			(hide yes)
			(effects
				(font
					(size 1 1)
					(thickness 0.15)
				)
			)
		)
		(property "Manufacturer" "Bourns"
			(at 0 0 180)
			(unlocked yes)
			(layer "F.Fab")
			(hide yes)
			(effects
				(font
					(size 1 1)
					(thickness 0.15)
				)
			)
		)
		(property "License" "Apache-2.0"
			(at 0 0 180)
			(unlocked yes)
			(layer "F.Fab")
			(hide yes)
			(effects
				(font
					(size 1 1)
					(thickness 0.15)
				)
			)
		)
		(property "Author" "Antmicro"
			(at 0 0 180)
			(unlocked yes)
			(layer "F.Fab")
			(hide yes)
			(effects
				(font
					(size 1 1)
					(thickness 0.15)
				)
			)
		)
		(property "Val" "49k9"
			(at 0 0 180)
			(unlocked yes)
			(layer "F.Fab")
			(hide yes)
			(effects
				(font
					(size 1 1)
					(thickness 0.15)
				)
			)
		)
		(property "Tolerance" "1%"
			(at 0 0 180)
			(unlocked yes)
			(layer "F.Fab")
			(hide yes)
			(effects
				(font
					(size 1 1)
					(thickness 0.15)
				)
			)
		)
		(sheetname "/HDMI + SD Card/")
		(sheetfile "hdmi-sd-card.kicad_sch")
		(attr smd)
		(fp_rect
			(start -0.925 -0.47)
			(end 0.925 0.47)
			(stroke
				(width 0.05)
				(type default)
			)
			(fill no)
			(layer "F.CrtYd")
		)
		(fp_rect
			(start -0.5 -0.25)
			(end 0.5 0.25)
			(stroke
				(width 0.15)
				(type solid)
			)
			(fill no)
			(layer "F.Fab")
		)
		(fp_text user "Author: Antmicro"
			(at -0.95 4.169 180)
			(layer "F.Fab")
			(effects
				(font
					(size 0.7 0.7)
					(thickness 0.15)
				)
				(justify left bottom)
			)
		)
		(fp_text user "License: Apache-2.0"
			(at -0.95 5.169 180)
			(layer "F.Fab")
			(effects
				(font
					(size 0.7 0.7)
					(thickness 0.15)
				)
				(justify left bottom)
			)
		)
		(fp_text user "${REFERENCE}"
			(at -0.95 3.168 180)
			(layer "F.Fab")
			(effects
				(font
					(size 0.7 0.7)
					(thickness 0.15)
				)
				(justify left bottom)
			)
		)
		(pad "1" smd roundrect
			(at -0.48 0 180)
			(size 0.59 0.64)
			(layers "F.Cu" "F.Mask" "F.Paste")
			(roundrect_rratio 0.25)
			(net 676 "Net-(L6-Pad2)")
			(pintype "passive")
		)
		(pad "2" smd roundrect
			(at 0.48 0 180)
			(size 0.59 0.64)
			(layers "F.Cu" "F.Mask" "F.Paste")
			(roundrect_rratio 0.25)
			(net 322 "Net-(C300-Pad2)")
			(pintype "passive")
		)
	)
	(footprint "antmicro-footprints:Conn_JST_SH_1x4_BM04B-SRSS-TB-LF-SN"
		(layer "F.Cu")
		(at 255.975 184.975)
		(property "Reference" "J12"
			(at -2.195 4.17 0)
			(layer "F.SilkS")
			(effects
				(font
					(size 0.7 0.7)
					(thickness 0.15)
				)
				(justify left bottom)
			)
		)
		(property "Value" "JST_SH_1x4_BM04B-SRSS-TB-LF-SN"
			(at -3.25 5 0)
			(layer "F.Fab")
			(effects
				(font
					(size 0.7 0.7)
					(thickness 0.15)
				)
				(justify left bottom)
			)
		)
		(property "Datasheet" "https://www.jst-mfg.com/product/pdf/eng/eSH.pdf"
			(at 0 0 0)
			(layer "F.Fab")
			(hide yes)
			(effects
				(font
					(size 1.27 1.27)
					(thickness 0.15)
				)
			)
		)
		(property "MPN" "BM04B-SRSS-TB(LF)(SN) "
			(at 0 0 0)
			(unlocked yes)
			(layer "F.Fab")
			(hide yes)
			(effects
				(font
					(size 1 1)
					(thickness 0.15)
				)
			)
		)
		(property "Manufacturer" "JST Automotive Connectors"
			(at 0 0 0)
			(unlocked yes)
			(layer "F.Fab")
			(hide yes)
			(effects
				(font
					(size 1 1)
					(thickness 0.15)
				)
			)
		)
		(property "Author" "Antmicro"
			(at 0 0 0)
			(unlocked yes)
			(layer "F.Fab")
			(hide yes)
			(effects
				(font
					(size 1 1)
					(thickness 0.15)
				)
			)
		)
		(property "License" "Apache-2.0"
			(at 0 0 0)
			(unlocked yes)
			(layer "F.Fab")
			(hide yes)
			(effects
				(font
					(size 1 1)
					(thickness 0.15)
				)
			)
		)
		(sheetname "/I^{2}C + I3C/")
		(sheetfile "i2c.kicad_sch")
		(attr smd)
		(fp_line
			(start -1.125 -2.999)
			(end -1.125 -2.201)
			(stroke
				(width 0.15)
				(type solid)
			)
			(layer "F.SilkS")
		)
		(fp_line
			(start -1.125 2.999)
			(end -1.125 2.201)
			(stroke
				(width 0.15)
				(type solid)
			)
			(layer "F.SilkS")
		)
		(fp_line
			(start -0.251 -2.999)
			(end -1.125 -2.999)
			(stroke
				(width 0.15)
				(type solid)
			)
			(layer "F.SilkS")
		)
		(fp_line
			(start -0.251 2.999)
			(end -1.125 2.999)
			(stroke
				(width 0.15)
				(type solid)
			)
			(layer "F.SilkS")
		)
		(fp_line
			(start 1.774 -1.7)
			(end 1.774 1.702)
			(stroke
				(width 0.15)
				(type solid)
			)
			(layer "F.SilkS")
		)
		(fp_circle
			(center -1.6 -2.1)
			(end -1.55 -2.1)
			(stroke
				(width 0.15)
				(type solid)
			)
			(fill yes)
			(layer "F.SilkS")
		)
		(fp_rect
			(start -2.05 -3.95)
			(end 2.05 3.95)
			(stroke
				(width 0.05)
				(type solid)
			)
			(fill no)
			(layer "F.CrtYd")
		)
		(fp_rect
			(start -1.8 -3)
			(end 1.8 3)
			(stroke
				(width 0.15)
				(type solid)
			)
			(fill no)
			(layer "F.Fab")
		)
		(fp_text user "Author: Antmicro"
			(at -3.25 7 0)
			(layer "F.Fab")
			(effects
				(font
					(size 0.7 0.7)
					(thickness 0.15)
				)
				(justify left bottom)
			)
		)
		(fp_text user "${REFERENCE}"
			(at -3.25 8.2 0)
			(layer "F.Fab")
			(effects
				(font
					(size 0.7 0.7)
					(thickness 0.15)
				)
				(justify left bottom)
			)
		)
		(fp_text user "License: Apache-2.0"
			(at -3.25 9.4 0)
			(layer "F.Fab")
			(effects
				(font
					(size 0.7 0.7)
					(thickness 0.15)
				)
				(justify left bottom)
			)
		)
		(pad "1" smd roundrect
			(at -1.45 -1.5 270)
			(size 0.6 1.55)
			(layers "F.Cu" "F.Mask" "F.Paste")
			(roundrect_rratio 0.25)
			(net 1 "GND")
			(pintype "passive")
		)
		(pad "2" smd roundrect
			(at -1.45 -0.5 270)
			(size 0.6 1.55)
			(layers "F.Cu" "F.Mask" "F.Paste")
			(roundrect_rratio 0.25)
			(net 664 "Net-(C325-Pad2)")
			(pintype "passive")
		)
		(pad "3" smd roundrect
			(at -1.45 0.5 270)
			(size 0.6 1.55)
			(layers "F.Cu" "F.Mask" "F.Paste")
			(roundrect_rratio 0.25)
			(net 369 "/I^{2}C + I3C/I3C_EXT.SCL")
			(pintype "passive")
		)
		(pad "4" smd roundrect
			(at -1.45 1.5 270)
			(size 0.6 1.55)
			(layers "F.Cu" "F.Mask" "F.Paste")
			(roundrect_rratio 0.25)
			(net 368 "/I^{2}C + I3C/I3C_EXT.SDA")
			(pintype "passive")
		)
		(pad "MP" smd roundrect
			(at 1.075 -2.8 270)
			(size 1.2 1.8)
			(layers "F.Cu" "F.Mask" "F.Paste")
			(roundrect_rratio 0.25)
			(net 1 "GND")
			(pintype "passive")
		)
		(pad "MP" smd roundrect
			(at 1.075 2.8 270)
			(size 1.2 1.8)
			(layers "F.Cu" "F.Mask" "F.Paste")
			(roundrect_rratio 0.25)
			(net 1 "GND")
			(pintype "passive")
		)
	)
	(footprint "antmicro-footprints:R_0402_1005Metric"
		(layer "F.Cu")
		(at 127.681 168.3125 90)
		(descr "Resistor SMD 0402")
		(tags "resistor SMD 0402")
		(property "Reference" "R77"
			(at -3.15 0.619 90)
			(layer "F.SilkS")
			(effects
				(font
					(size 0.7 0.7)
					(thickness 0.15)
				)
				(justify left bottom)
			)
		)
		(property "Value" "R_64k9_0402"
			(at -1.011843 1.772047 90)
			(layer "F.Fab")
			(effects
				(font
					(size 0.7 0.7)
					(thickness 0.15)
				)
				(justify left bottom)
			)
		)
		(property "Datasheet" "https://www.bourns.com/docs/product-datasheets/cr.pdf"
			(at 0 0 90)
			(layer "F.Fab")
			(hide yes)
			(effects
				(font
					(size 1.27 1.27)
					(thickness 0.15)
				)
			)
		)
		(property "MPN" "CR0402-FX-6492GLF"
			(at 0 0 90)
			(unlocked yes)
			(layer "F.Fab")
			(hide yes)
			(effects
				(font
					(size 1 1)
					(thickness 0.15)
				)
			)
		)
		(property "Manufacturer" "Bourns"
			(at 0 0 90)
			(unlocked yes)
			(layer "F.Fab")
			(hide yes)
			(effects
				(font
					(size 1 1)
					(thickness 0.15)
				)
			)
		)
		(property "License" "Apache-2.0"
			(at 0 0 90)
			(unlocked yes)
			(layer "F.Fab")
			(hide yes)
			(effects
				(font
					(size 1 1)
					(thickness 0.15)
				)
			)
		)
		(property "Author" "Antmicro"
			(at 0 0 90)
			(unlocked yes)
			(layer "F.Fab")
			(hide yes)
			(effects
				(font
					(size 1 1)
					(thickness 0.15)
				)
			)
		)
		(property "Val" "64k9"
			(at 0 0 90)
			(unlocked yes)
			(layer "F.Fab")
			(hide yes)
			(effects
				(font
					(size 1 1)
					(thickness 0.15)
				)
			)
		)
		(property "Tolerance" "1%"
			(at 0 0 90)
			(unlocked yes)
			(layer "F.Fab")
			(hide yes)
			(effects
				(font
					(size 1 1)
					(thickness 0.15)
				)
			)
		)
		(sheetname "/HDMI + SD Card/")
		(sheetfile "hdmi-sd-card.kicad_sch")
		(attr smd exclude_from_bom)
		(fp_rect
			(start -0.925 -0.47)
			(end 0.925 0.47)
			(stroke
				(width 0.05)
				(type default)
			)
			(fill no)
			(layer "F.CrtYd")
		)
		(fp_rect
			(start -0.5 -0.25)
			(end 0.5 0.25)
			(stroke
				(width 0.15)
				(type solid)
			)
			(fill no)
			(layer "F.Fab")
		)
		(fp_text user "License: Apache-2.0"
			(at -0.95 5.169 90)
			(layer "F.Fab")
			(effects
				(font
					(size 0.7 0.7)
					(thickness 0.15)
				)
				(justify left bottom)
			)
		)
		(fp_text user "${REFERENCE}"
			(at -0.95 3.168 90)
			(layer "F.Fab")
			(effects
				(font
					(size 0.7 0.7)
					(thickness 0.15)
				)
				(justify left bottom)
			)
		)
		(fp_text user "Author: Antmicro"
			(at -0.95 4.169 90)
			(layer "F.Fab")
			(effects
				(font
					(size 0.7 0.7)
					(thickness 0.15)
				)
				(justify left bottom)
			)
		)
		(pad "1" smd roundrect
			(at -0.48 0 90)
			(size 0.59 0.64)
			(layers "F.Cu" "F.Mask" "F.Paste")
			(roundrect_rratio 0.25)
			(net 1 "GND")
			(pintype "passive")
		)
		(pad "2" smd roundrect
			(at 0.48 0 90)
			(size 0.59 0.64)
			(layers "F.Cu" "F.Mask" "F.Paste")
			(roundrect_rratio 0.25)
			(net 710 "/HDMI + SD Card/I2C_EN{slash}PIN")
			(pintype "passive")
		)
	)
)
